# T6G (Grand Teton) — schematic netlist excerpt (pin names and nets, part order shuffled) for the footprints in the layout excerpt that follows; sources: Cadence DE-HDL packaged netlist, KiCad conversion of 04192023_DAF0TMB3IC0_F0TG_MB_C_brd_V02_OCP.brd

C182  Q_CAP  10UF 25V 10% X6S  pkg C0805  page 101 : A = P12V_MEM_CPU1 ; B = GND
PR3337  Q_RES  0 5% CHIP  pkg 0402LF  page 189 : A = P5V_AUX_MODE ; B = GND
R766  Q_RES  23.2K 1% CHIP  pkg 0402LF  page 94 : A = PD_CHI_CPU0_DIMM_SAA ; B = GND

(kicad_pcb
	(version 20260206)
	(generator "pcbnew")
	(generator_version "10.0")
	(general
		(thickness 1.6)
		(legacy_teardrops no)
	)
	(paper "A4")
	(title_block
		(title "04192023_DAF0TMB3IC0_F0TG_MB_C_brd_V02_OCP.brd")
		(comment 1 "Grand Teton / footprints 7360-7362 of 8354")
	)
	(layers
		(0 "F.Cu" signal "TOP")
		(4 "In1.Cu" signal "GND")
		(6 "In2.Cu" signal "IN1")
		(8 "In3.Cu" signal "GND1")
		(10 "In4.Cu" signal "IN2")
		(12 "In5.Cu" signal "GND2")
		(14 "In6.Cu" signal "IN3")
		(16 "In7.Cu" signal "GND3")
		(18 "In8.Cu" signal "VCC")
		(20 "In9.Cu" signal "VCC1")
		(22 "In10.Cu" signal "GND4")
		(24 "In11.Cu" signal "IN4")
		(26 "In12.Cu" signal "GND5")
		(28 "In13.Cu" signal "IN5")
		(30 "In14.Cu" signal "GND6")
		(32 "In15.Cu" signal "IN6")
		(34 "In16.Cu" signal "GND7")
		(2 "B.Cu" signal "BOTTOM")
		(9 "F.Adhes" user "F.Adhesive")
		(11 "B.Adhes" user "B.Adhesive")
		(13 "F.Paste" user "Package Geometry/Pastemask Top")
		(15 "B.Paste" user "Package Geometry/Pastemask Bottom")
		(5 "F.SilkS" user "Ref Des/Silkscreen Top")
		(7 "B.SilkS" user "Ref Des/Silkscreen Bottom")
		(1 "F.Mask" user "Board Geometry/Soldermask Top")
		(3 "B.Mask" user "Board Geometry/Soldermask Bottom")
		(17 "Dwgs.User" user "User.Drawings")
		(19 "Cmts.User" user "User.Comments")
		(21 "Eco1.User" user "User.Eco1")
		(23 "Eco2.User" user "User.Eco2")
		(25 "Edge.Cuts" user "Board Geometry/Outline")
		(27 "Margin" user)
		(31 "F.CrtYd" user "Package Geometry/Place Bound Top")
		(29 "B.CrtYd" user "Package Geometry/Place Bound Bottom")
		(35 "F.Fab" user "Ref Des/Assembly Top")
		(33 "B.Fab" user "Ref Des/Assembly Bottom")
	)
	(footprint ""
		(layer "B.Cu")
		(at 32.69615 -192.66027 180)
		(property "Reference" "C182"
			(at 0 0 0)
			(layer "B.SilkS")
			(hide yes)
			(effects
				(font
					(size 1.27 1.27)
				)
				(justify mirror)
			)
		)
		(property "Value" ""
			(at 0 0 0)
			(layer "B.Fab")
			(effects
				(font
					(size 1.27 1.27)
				)
				(justify mirror)
			)
		)
		(duplicate_pad_numbers_are_jumpers no)
		(fp_line
			(start 1.524 0.762)
			(end 1.524 -0.762)
			(stroke
				(width 0.1524)
				(type default)
			)
			(layer "B.SilkS")
		)
		(fp_line
			(start 1.524 -0.762)
			(end -1.524 -0.762)
			(stroke
				(width 0.1524)
				(type default)
			)
			(layer "B.SilkS")
		)
		(fp_line
			(start -1.524 0.762)
			(end 1.524 0.762)
			(stroke
				(width 0.1524)
				(type default)
			)
			(layer "B.SilkS")
		)
		(fp_line
			(start -1.524 -0.762)
			(end -1.524 0.762)
			(stroke
				(width 0.1524)
				(type default)
			)
			(layer "B.SilkS")
		)
		(fp_line
			(start 1.1049 0.724916)
			(end -1.1049 0.724916)
			(stroke
				(width 0.1)
				(type default)
			)
			(layer "B.Fab")
		)
		(fp_line
			(start 1.1049 -0.724916)
			(end 1.1049 0.724916)
			(stroke
				(width 0.1)
				(type default)
			)
			(layer "B.Fab")
		)
		(fp_line
			(start -1.1049 0.724916)
			(end -1.1049 -0.724916)
			(stroke
				(width 0.1)
				(type default)
			)
			(layer "B.Fab")
		)
		(fp_line
			(start -1.1049 -0.724916)
			(end 1.1049 -0.724916)
			(stroke
				(width 0.1)
				(type default)
			)
			(layer "B.Fab")
		)
		(pad "1" smd rect
			(at 0.889 0 180)
			(size 1.016 1.27)
			(layers "B.Cu" "B.Mask" "B.Paste")
			(net "P12V_MEM_CPU1")
		)
		(pad "2" smd rect
			(at -0.889 0 180)
			(size 1.016 1.27)
			(layers "B.Cu" "B.Mask" "B.Paste")
			(net "GND")
		)
	)
	(footprint ""
		(layer "B.Cu")
		(at 408.671776 -141.40942)
		(property "Reference" "PR3337"
			(at 0 0 0)
			(layer "B.SilkS")
			(hide yes)
			(effects
				(font
					(size 1.27 1.27)
				)
				(justify mirror)
			)
		)
		(property "Value" ""
			(at 0 0 0)
			(layer "B.Fab")
			(effects
				(font
					(size 1.27 1.27)
				)
				(justify mirror)
			)
		)
		(duplicate_pad_numbers_are_jumpers no)
		(fp_line
			(start -0.7874 -0.4064)
			(end -0.7874 0.4064)
			(stroke
				(width 0.1524)
				(type default)
			)
			(layer "B.SilkS")
		)
		(fp_line
			(start -0.7874 0.4064)
			(end 0.7874 0.4064)
			(stroke
				(width 0.1524)
				(type default)
			)
			(layer "B.SilkS")
		)
		(fp_line
			(start 0.7874 -0.4064)
			(end -0.7874 -0.4064)
			(stroke
				(width 0.1524)
				(type default)
			)
			(layer "B.SilkS")
		)
		(fp_line
			(start 0.7874 0.4064)
			(end 0.7874 -0.4064)
			(stroke
				(width 0.1524)
				(type default)
			)
			(layer "B.SilkS")
		)
		(fp_line
			(start -0.67945 -0.3048)
			(end -0.67945 0.3048)
			(stroke
				(width 0.1)
				(type default)
			)
			(layer "B.Fab")
		)
		(fp_line
			(start -0.67945 0.3048)
			(end -0.120396 0.3048)
			(stroke
				(width 0.1)
				(type default)
			)
			(layer "B.Fab")
		)
		(fp_line
			(start -0.12065 -0.3048)
			(end -0.67945 -0.3048)
			(stroke
				(width 0.1)
				(type default)
			)
			(layer "B.Fab")
		)
		(fp_line
			(start -0.12065 -0.2794)
			(end -0.12065 -0.3048)
			(stroke
				(width 0.1)
				(type default)
			)
			(layer "B.Fab")
		)
		(fp_line
			(start -0.120396 0.2794)
			(end 0.12065 0.2794)
			(stroke
				(width 0.1)
				(type default)
			)
			(layer "B.Fab")
		)
		(fp_line
			(start -0.120396 0.3048)
			(end -0.120396 0.2794)
			(stroke
				(width 0.1)
				(type default)
			)
			(layer "B.Fab")
		)
		(fp_line
			(start 0.12065 -0.305054)
			(end 0.12065 -0.2794)
			(stroke
				(width 0.1)
				(type default)
			)
			(layer "B.Fab")
		)
		(fp_line
			(start 0.12065 -0.2794)
			(end -0.12065 -0.2794)
			(stroke
				(width 0.1)
				(type default)
			)
			(layer "B.Fab")
		)
		(fp_line
			(start 0.12065 0.2794)
			(end 0.12065 0.3048)
			(stroke
				(width 0.1)
				(type default)
			)
			(layer "B.Fab")
		)
		(fp_line
			(start 0.12065 0.3048)
			(end 0.67945 0.3048)
			(stroke
				(width 0.1)
				(type default)
			)
			(layer "B.Fab")
		)
		(fp_line
			(start 0.67945 -0.305054)
			(end 0.12065 -0.305054)
			(stroke
				(width 0.1)
				(type default)
			)
			(layer "B.Fab")
		)
		(fp_line
			(start 0.67945 0.3048)
			(end 0.67945 -0.305054)
			(stroke
				(width 0.1)
				(type default)
			)
			(layer "B.Fab")
		)
		(pad "1" smd circle
			(at 0.40005 0 180)
			(size 0 0)
			(layers "B.Cu" "B.Mask" "B.Paste")
			(net "P5V_AUX_MODE")
		)
		(pad "2" smd circle
			(at -0.40005 0 180)
			(size 0 0)
			(layers "B.Cu" "B.Mask" "B.Paste")
			(net "GND")
		)
	)
	(footprint ""
		(layer "B.Cu")
		(at 428.211742 -194.88531 180)
		(property "Reference" "R766"
			(at 0 0 0)
			(layer "B.SilkS")
			(hide yes)
			(effects
				(font
					(size 1.27 1.27)
				)
				(justify mirror)
			)
		)
		(property "Value" ""
			(at 0 0 0)
			(layer "B.Fab")
			(effects
				(font
					(size 1.27 1.27)
				)
				(justify mirror)
			)
		)
		(duplicate_pad_numbers_are_jumpers no)
		(fp_line
			(start 0.7874 0.4064)
			(end 0.7874 -0.4064)
			(stroke
				(width 0.1524)
				(type default)
			)
			(layer "B.SilkS")
		)
		(fp_line
			(start 0.7874 -0.4064)
			(end -0.7874 -0.4064)
			(stroke
				(width 0.1524)
				(type default)
			)
			(layer "B.SilkS")
		)
		(fp_line
			(start -0.7874 0.4064)
			(end 0.7874 0.4064)
			(stroke
				(width 0.1524)
				(type default)
			)
			(layer "B.SilkS")
		)
		(fp_line
			(start -0.7874 -0.4064)
			(end -0.7874 0.4064)
			(stroke
				(width 0.1524)
				(type default)
			)
			(layer "B.SilkS")
		)
		(fp_line
			(start 0.67945 0.3048)
			(end 0.67945 -0.305054)
			(stroke
				(width 0.1)
				(type default)
			)
			(layer "B.Fab")
		)
		(fp_line
			(start 0.67945 -0.305054)
			(end 0.12065 -0.305054)
			(stroke
				(width 0.1)
				(type default)
			)
			(layer "B.Fab")
		)
		(fp_line
			(start 0.12065 0.3048)
			(end 0.67945 0.3048)
			(stroke
				(width 0.1)
				(type default)
			)
			(layer "B.Fab")
		)
		(fp_line
			(start 0.12065 0.2794)
			(end 0.12065 0.3048)
			(stroke
				(width 0.1)
				(type default)
			)
			(layer "B.Fab")
		)
		(fp_line
			(start 0.12065 -0.2794)
			(end -0.12065 -0.2794)
			(stroke
				(width 0.1)
				(type default)
			)
			(layer "B.Fab")
		)
		(fp_line
			(start 0.12065 -0.305054)
			(end 0.12065 -0.2794)
			(stroke
				(width 0.1)
				(type default)
			)
			(layer "B.Fab")
		)
		(fp_line
			(start -0.120396 0.3048)
			(end -0.120396 0.2794)
			(stroke
				(width 0.1)
				(type default)
			)
			(layer "B.Fab")
		)
		(fp_line
			(start -0.120396 0.2794)
			(end 0.12065 0.2794)
			(stroke
				(width 0.1)
				(type default)
			)
			(layer "B.Fab")
		)
		(fp_line
			(start -0.12065 -0.2794)
			(end -0.12065 -0.3048)
			(stroke
				(width 0.1)
				(type default)
			)
			(layer "B.Fab")
		)
		(fp_line
			(start -0.12065 -0.3048)
			(end -0.67945 -0.3048)
			(stroke
				(width 0.1)
				(type default)
			)
			(layer "B.Fab")
		)
		(fp_line
			(start -0.67945 0.3048)
			(end -0.120396 0.3048)
			(stroke
				(width 0.1)
				(type default)
			)
			(layer "B.Fab")
		)
		(fp_line
			(start -0.67945 -0.3048)
			(end -0.67945 0.3048)
			(stroke
				(width 0.1)
				(type default)
			)
			(layer "B.Fab")
		)
		(pad "1" smd circle
			(at 0.40005 0)
			(size 0 0)
			(layers "B.Cu" "B.Mask" "B.Paste")
			(net "PD_CHI_CPU0_DIMM_SAA")
		)
		(pad "2" smd circle
			(at -0.40005 0)
			(size 0 0)
			(layers "B.Cu" "B.Mask" "B.Paste")
			(net "GND")
		)
	)
)
